# T6G (Grand Teton) — schematic netlist excerpt (pin names and nets, part order shuffled) for the footprints in the layout excerpt that follows; sources: Cadence DE-HDL packaged netlist, KiCad conversion of 04192023_DAF0TMB3IC0_F0TG_MB_C_brd_V02_OCP.brd

R8219  Q_RES  1K 1% EMPTY  pkg 0402LF  page 217 : A = SVID_PVDDCR_CPU1_P1_SVTO ; B = GND
R2413  Q_RES  33.2 1% CHIP  pkg 0402LF  page 150 : A = SMB_2_BMC_GPU_SCL ; B = SMB_PCIE2_3V3AUX_SCL_R0

(kicad_pcb
	(version 20260206)
	(generator "pcbnew")
	(generator_version "10.0")
	(general
		(thickness 1.6)
		(legacy_teardrops no)
	)
	(paper "A4")
	(title_block
		(title "04192023_DAF0TMB3IC0_F0TG_MB_C_brd_V02_OCP.brd")
		(comment 1 "Grand Teton / footprints 7376-7377 of 8354")
	)
	(layers
		(0 "F.Cu" signal "TOP")
		(4 "In1.Cu" signal "GND")
		(6 "In2.Cu" signal "IN1")
		(8 "In3.Cu" signal "GND1")
		(10 "In4.Cu" signal "IN2")
		(12 "In5.Cu" signal "GND2")
		(14 "In6.Cu" signal "IN3")
		(16 "In7.Cu" signal "GND3")
		(18 "In8.Cu" signal "VCC")
		(20 "In9.Cu" signal "VCC1")
		(22 "In10.Cu" signal "GND4")
		(24 "In11.Cu" signal "IN4")
		(26 "In12.Cu" signal "GND5")
		(28 "In13.Cu" signal "IN5")
		(30 "In14.Cu" signal "GND6")
		(32 "In15.Cu" signal "IN6")
		(34 "In16.Cu" signal "GND7")
		(2 "B.Cu" signal "BOTTOM")
		(9 "F.Adhes" user "F.Adhesive")
		(11 "B.Adhes" user "B.Adhesive")
		(13 "F.Paste" user "Package Geometry/Pastemask Top")
		(15 "B.Paste" user "Package Geometry/Pastemask Bottom")
		(5 "F.SilkS" user "Ref Des/Silkscreen Top")
		(7 "B.SilkS" user "Ref Des/Silkscreen Bottom")
		(1 "F.Mask" user "Board Geometry/Soldermask Top")
		(3 "B.Mask" user "Board Geometry/Soldermask Bottom")
		(17 "Dwgs.User" user "User.Drawings")
		(19 "Cmts.User" user "User.Comments")
		(21 "Eco1.User" user "User.Eco1")
		(23 "Eco2.User" user "User.Eco2")
		(25 "Edge.Cuts" user "Board Geometry/Outline")
		(27 "Margin" user)
		(31 "F.CrtYd" user "Package Geometry/Place Bound Top")
		(29 "B.CrtYd" user "Package Geometry/Place Bound Bottom")
		(35 "F.Fab" user "Ref Des/Assembly Top")
		(33 "B.Fab" user "Ref Des/Assembly Bottom")
	)
	(footprint ""
		(layer "B.Cu")
		(at 24.765 -358.775 180)
		(property "Reference" "R8219"
			(at 0 0 0)
			(layer "B.SilkS")
			(hide yes)
			(effects
				(font
					(size 1.27 1.27)
				)
				(justify mirror)
			)
		)
		(property "Value" ""
			(at 0 0 0)
			(layer "B.Fab")
			(effects
				(font
					(size 1.27 1.27)
				)
				(justify mirror)
			)
		)
		(duplicate_pad_numbers_are_jumpers no)
		(fp_line
			(start 0.7874 0.4064)
			(end 0.7874 -0.4064)
			(stroke
				(width 0.1524)
				(type default)
			)
			(layer "B.SilkS")
		)
		(fp_line
			(start 0.7874 -0.4064)
			(end -0.7874 -0.4064)
			(stroke
				(width 0.1524)
				(type default)
			)
			(layer "B.SilkS")
		)
		(fp_line
			(start -0.7874 0.4064)
			(end 0.7874 0.4064)
			(stroke
				(width 0.1524)
				(type default)
			)
			(layer "B.SilkS")
		)
		(fp_line
			(start -0.7874 -0.4064)
			(end -0.7874 0.4064)
			(stroke
				(width 0.1524)
				(type default)
			)
			(layer "B.SilkS")
		)
		(fp_line
			(start 0.67945 0.3048)
			(end 0.67945 -0.305054)
			(stroke
				(width 0.1)
				(type default)
			)
			(layer "B.Fab")
		)
		(fp_line
			(start 0.67945 -0.305054)
			(end 0.12065 -0.305054)
			(stroke
				(width 0.1)
				(type default)
			)
			(layer "B.Fab")
		)
		(fp_line
			(start 0.12065 0.3048)
			(end 0.67945 0.3048)
			(stroke
				(width 0.1)
				(type default)
			)
			(layer "B.Fab")
		)
		(fp_line
			(start 0.12065 0.2794)
			(end 0.12065 0.3048)
			(stroke
				(width 0.1)
				(type default)
			)
			(layer "B.Fab")
		)
		(fp_line
			(start 0.12065 -0.2794)
			(end -0.12065 -0.2794)
			(stroke
				(width 0.1)
				(type default)
			)
			(layer "B.Fab")
		)
		(fp_line
			(start 0.12065 -0.305054)
			(end 0.12065 -0.2794)
			(stroke
				(width 0.1)
				(type default)
			)
			(layer "B.Fab")
		)
		(fp_line
			(start -0.120396 0.3048)
			(end -0.120396 0.2794)
			(stroke
				(width 0.1)
				(type default)
			)
			(layer "B.Fab")
		)
		(fp_line
			(start -0.120396 0.2794)
			(end 0.12065 0.2794)
			(stroke
				(width 0.1)
				(type default)
			)
			(layer "B.Fab")
		)
		(fp_line
			(start -0.12065 -0.2794)
			(end -0.12065 -0.3048)
			(stroke
				(width 0.1)
				(type default)
			)
			(layer "B.Fab")
		)
		(fp_line
			(start -0.12065 -0.3048)
			(end -0.67945 -0.3048)
			(stroke
				(width 0.1)
				(type default)
			)
			(layer "B.Fab")
		)
		(fp_line
			(start -0.67945 0.3048)
			(end -0.120396 0.3048)
			(stroke
				(width 0.1)
				(type default)
			)
			(layer "B.Fab")
		)
		(fp_line
			(start -0.67945 -0.3048)
			(end -0.67945 0.3048)
			(stroke
				(width 0.1)
				(type default)
			)
			(layer "B.Fab")
		)
		(pad "1" smd circle
			(at 0.40005 0)
			(size 0 0)
			(layers "B.Cu" "B.Mask" "B.Paste")
			(net "SVID_PVDDCR_CPU1_P1_SVTO")
		)
		(pad "2" smd circle
			(at -0.40005 0)
			(size 0 0)
			(layers "B.Cu" "B.Mask" "B.Paste")
			(net "GND")
		)
	)
	(footprint ""
		(layer "B.Cu")
		(at 156.17063 -13.762228 90)
		(property "Reference" "R2413"
			(at 0 0 90)
			(layer "B.SilkS")
			(hide yes)
			(effects
				(font
					(size 1.27 1.27)
				)
				(justify mirror)
			)
		)
		(property "Value" ""
			(at 0 0 90)
			(layer "B.Fab")
			(effects
				(font
					(size 1.27 1.27)
				)
				(justify mirror)
			)
		)
		(duplicate_pad_numbers_are_jumpers no)
		(fp_line
			(start 0.7874 -0.4064)
			(end -0.7874 -0.4064)
			(stroke
				(width 0.1524)
				(type default)
			)
			(layer "B.SilkS")
		)
		(fp_line
			(start -0.7874 -0.4064)
			(end -0.7874 0.4064)
			(stroke
				(width 0.1524)
				(type default)
			)
			(layer "B.SilkS")
		)
		(fp_line
			(start 0.7874 0.4064)
			(end 0.7874 -0.4064)
			(stroke
				(width 0.1524)
				(type default)
			)
			(layer "B.SilkS")
		)
		(fp_line
			(start -0.7874 0.4064)
			(end 0.7874 0.4064)
			(stroke
				(width 0.1524)
				(type default)
			)
			(layer "B.SilkS")
		)
		(fp_line
			(start 0.67945 -0.305054)
			(end 0.12065 -0.305054)
			(stroke
				(width 0.1)
				(type default)
			)
			(layer "B.Fab")
		)
		(fp_line
			(start 0.12065 -0.305054)
			(end 0.12065 -0.2794)
			(stroke
				(width 0.1)
				(type default)
			)
			(layer "B.Fab")
		)
		(fp_line
			(start -0.12065 -0.3048)
			(end -0.67945 -0.3048)
			(stroke
				(width 0.1)
				(type default)
			)
			(layer "B.Fab")
		)
		(fp_line
			(start -0.67945 -0.3048)
			(end -0.67945 0.3048)
			(stroke
				(width 0.1)
				(type default)
			)
			(layer "B.Fab")
		)
		(fp_line
			(start 0.12065 -0.2794)
			(end -0.12065 -0.2794)
			(stroke
				(width 0.1)
				(type default)
			)
			(layer "B.Fab")
		)
		(fp_line
			(start -0.12065 -0.2794)
			(end -0.12065 -0.3048)
			(stroke
				(width 0.1)
				(type default)
			)
			(layer "B.Fab")
		)
		(fp_line
			(start 0.12065 0.2794)
			(end 0.12065 0.3048)
			(stroke
				(width 0.1)
				(type default)
			)
			(layer "B.Fab")
		)
		(fp_line
			(start -0.120396 0.2794)
			(end 0.12065 0.2794)
			(stroke
				(width 0.1)
				(type default)
			)
			(layer "B.Fab")
		)
		(fp_line
			(start 0.67945 0.3048)
			(end 0.67945 -0.305054)
			(stroke
				(width 0.1)
				(type default)
			)
			(layer "B.Fab")
		)
		(fp_line
			(start 0.12065 0.3048)
			(end 0.67945 0.3048)
			(stroke
				(width 0.1)
				(type default)
			)
			(layer "B.Fab")
		)
		(fp_line
			(start -0.120396 0.3048)
			(end -0.120396 0.2794)
			(stroke
				(width 0.1)
				(type default)
			)
			(layer "B.Fab")
		)
		(fp_line
			(start -0.67945 0.3048)
			(end -0.120396 0.3048)
			(stroke
				(width 0.1)
				(type default)
			)
			(layer "B.Fab")
		)
		(pad "1" smd circle
			(at 0.40005 0 270)
			(size 0 0)
			(layers "B.Cu" "B.Mask" "B.Paste")
			(net "SMB_2_BMC_GPU_SCL")
		)
		(pad "2" smd circle
			(at -0.40005 0 270)
			(size 0 0)
			(layers "B.Cu" "B.Mask" "B.Paste")
			(net "SMB_PCIE2_3V3AUX_SCL_R0")
		)
	)
)
